(kicad_pcb
	(version 20260206)
	(generator "pcbnew")
	(generator_version "10.0")
	(general
		(thickness 1.6)
		(legacy_teardrops no)
	)
	(paper "A4")
	(title_block
		(title "01162023_DA0F0TEBIF0_F0T_Expander_BD_F_brd_V02_OCP.brd")
		(comment 1 "Grand Teton / footprints 3269-3275 of 9728")
	)
	(layers
		(0 "F.Cu" signal "TOP")
		(4 "In1.Cu" signal "GND")
		(6 "In2.Cu" signal "VCC")
		(8 "In3.Cu" signal "VCC1")
		(10 "In4.Cu" signal "GND1")
		(12 "In5.Cu" signal "IN1")
		(14 "In6.Cu" signal "GND2")
		(16 "In7.Cu" signal "IN2")
		(18 "In8.Cu" signal "GND3")
		(20 "In9.Cu" signal "IN3")
		(22 "In10.Cu" signal "GND4")
		(24 "In11.Cu" signal "IN4")
		(26 "In12.Cu" signal "GND5")
		(28 "In13.Cu" signal "IN5")
		(30 "In14.Cu" signal "GND6")
		(32 "In15.Cu" signal "IN6")
		(34 "In16.Cu" signal "GND7")
		(2 "B.Cu" signal "BOTTOM")
		(9 "F.Adhes" user "F.Adhesive")
		(11 "B.Adhes" user "B.Adhesive")
		(13 "F.Paste" user "Package Geometry/Pastemask Top")
		(15 "B.Paste" user "Package Geometry/Pastemask Bottom")
		(5 "F.SilkS" user "Ref Des/Silkscreen Top")
		(7 "B.SilkS" user "Ref Des/Silkscreen Bottom")
		(1 "F.Mask" user "Board Geometry/Soldermask Top")
		(3 "B.Mask" user "Board Geometry/Soldermask Bottom")
		(17 "Dwgs.User" user "User.Drawings")
		(19 "Cmts.User" user "User.Comments")
		(21 "Eco1.User" user "User.Eco1")
		(23 "Eco2.User" user "User.Eco2")
		(25 "Edge.Cuts" user "Board Geometry/Outline")
		(27 "Margin" user)
		(31 "F.CrtYd" user "Package Geometry/Place Bound Top")
		(29 "B.CrtYd" user "Package Geometry/Place Bound Bottom")
		(35 "F.Fab" user "Ref Des/Assembly Top")
		(33 "B.Fab" user "Ref Des/Assembly Bottom")
	)
	(footprint ""
		(layer "F.Cu")
		(at 347.559122 -264.95756 180)
		(property "Reference" "PR7137"
			(at 0 0 180)
			(layer "F.SilkS")
			(hide yes)
			(effects
				(font
					(size 1.27 1.27)
				)
			)
		)
		(property "Value" ""
			(at 0 0 180)
			(layer "F.Fab")
			(effects
				(font
					(size 1.27 1.27)
				)
			)
		)
		(duplicate_pad_numbers_are_jumpers no)
		(fp_line
			(start 0.7874 0.4064)
			(end -0.7874 0.4064)
			(stroke
				(width 0.1524)
				(type default)
			)
			(layer "F.SilkS")
		)
		(fp_line
			(start 0.7874 -0.4064)
			(end 0.7874 0.4064)
			(stroke
				(width 0.1524)
				(type default)
			)
			(layer "F.SilkS")
		)
		(fp_line
			(start -0.7874 0.4064)
			(end -0.7874 -0.4064)
			(stroke
				(width 0.1524)
				(type default)
			)
			(layer "F.SilkS")
		)
		(fp_line
			(start -0.7874 -0.4064)
			(end 0.7874 -0.4064)
			(stroke
				(width 0.1524)
				(type default)
			)
			(layer "F.SilkS")
		)
		(fp_line
			(start 0.67945 0.3048)
			(end 0.120396 0.3048)
			(stroke
				(width 0.1)
				(type default)
			)
			(layer "F.Fab")
		)
		(fp_line
			(start 0.67945 -0.3048)
			(end 0.67945 0.3048)
			(stroke
				(width 0.1)
				(type default)
			)
			(layer "F.Fab")
		)
		(fp_line
			(start 0.12065 -0.2794)
			(end 0.12065 -0.3048)
			(stroke
				(width 0.1)
				(type default)
			)
			(layer "F.Fab")
		)
		(fp_line
			(start 0.12065 -0.3048)
			(end 0.67945 -0.3048)
			(stroke
				(width 0.1)
				(type default)
			)
			(layer "F.Fab")
		)
		(fp_line
			(start 0.120396 0.3048)
			(end 0.120396 0.2794)
			(stroke
				(width 0.1)
				(type default)
			)
			(layer "F.Fab")
		)
		(fp_line
			(start 0.120396 0.2794)
			(end -0.12065 0.2794)
			(stroke
				(width 0.1)
				(type default)
			)
			(layer "F.Fab")
		)
		(fp_line
			(start -0.12065 0.3048)
			(end -0.67945 0.3048)
			(stroke
				(width 0.1)
				(type default)
			)
			(layer "F.Fab")
		)
		(fp_line
			(start -0.12065 0.2794)
			(end -0.12065 0.3048)
			(stroke
				(width 0.1)
				(type default)
			)
			(layer "F.Fab")
		)
		(fp_line
			(start -0.12065 -0.2794)
			(end 0.12065 -0.2794)
			(stroke
				(width 0.1)
				(type default)
			)
			(layer "F.Fab")
		)
		(fp_line
			(start -0.12065 -0.305054)
			(end -0.12065 -0.2794)
			(stroke
				(width 0.1)
				(type default)
			)
			(layer "F.Fab")
		)
		(fp_line
			(start -0.67945 0.3048)
			(end -0.67945 -0.305054)
			(stroke
				(width 0.1)
				(type default)
			)
			(layer "F.Fab")
		)
		(fp_line
			(start -0.67945 -0.305054)
			(end -0.12065 -0.305054)
			(stroke
				(width 0.1)
				(type default)
			)
			(layer "F.Fab")
		)
		(pad "1" smd circle
			(at -0.40005 0 180)
			(size 0 0)
			(layers "F.Cu" "F.Mask" "F.Paste")
			(net "NC_P0V8_PEX2_ISEN5")
		)
		(pad "2" smd circle
			(at 0.40005 0 180)
			(size 0 0)
			(layers "F.Cu" "F.Mask" "F.Paste")
			(net "GND")
		)
	)
	(footprint ""
		(layer "F.Cu")
		(at 166.330884 -199.932798)
		(property "Reference" "R3406"
			(at 0 0 0)
			(layer "F.SilkS")
			(hide yes)
			(effects
				(font
					(size 1.27 1.27)
				)
			)
		)
		(property "Value" ""
			(at 0 0 0)
			(layer "F.Fab")
			(effects
				(font
					(size 1.27 1.27)
				)
			)
		)
		(duplicate_pad_numbers_are_jumpers no)
		(fp_line
			(start -0.7874 -0.4064)
			(end 0.7874 -0.4064)
			(stroke
				(width 0.1524)
				(type default)
			)
			(layer "F.SilkS")
		)
		(fp_line
			(start -0.7874 0.4064)
			(end -0.7874 -0.4064)
			(stroke
				(width 0.1524)
				(type default)
			)
			(layer "F.SilkS")
		)
		(fp_line
			(start 0.7874 -0.4064)
			(end 0.7874 0.4064)
			(stroke
				(width 0.1524)
				(type default)
			)
			(layer "F.SilkS")
		)
		(fp_line
			(start 0.7874 0.4064)
			(end -0.7874 0.4064)
			(stroke
				(width 0.1524)
				(type default)
			)
			(layer "F.SilkS")
		)
		(fp_line
			(start -0.67945 -0.305054)
			(end -0.12065 -0.305054)
			(stroke
				(width 0.1)
				(type default)
			)
			(layer "F.Fab")
		)
		(fp_line
			(start -0.67945 0.3048)
			(end -0.67945 -0.305054)
			(stroke
				(width 0.1)
				(type default)
			)
			(layer "F.Fab")
		)
		(fp_line
			(start -0.12065 -0.305054)
			(end -0.12065 -0.2794)
			(stroke
				(width 0.1)
				(type default)
			)
			(layer "F.Fab")
		)
		(fp_line
			(start -0.12065 -0.2794)
			(end 0.12065 -0.2794)
			(stroke
				(width 0.1)
				(type default)
			)
			(layer "F.Fab")
		)
		(fp_line
			(start -0.12065 0.2794)
			(end -0.12065 0.3048)
			(stroke
				(width 0.1)
				(type default)
			)
			(layer "F.Fab")
		)
		(fp_line
			(start -0.12065 0.3048)
			(end -0.67945 0.3048)
			(stroke
				(width 0.1)
				(type default)
			)
			(layer "F.Fab")
		)
		(fp_line
			(start 0.120396 0.2794)
			(end -0.12065 0.2794)
			(stroke
				(width 0.1)
				(type default)
			)
			(layer "F.Fab")
		)
		(fp_line
			(start 0.120396 0.3048)
			(end 0.120396 0.2794)
			(stroke
				(width 0.1)
				(type default)
			)
			(layer "F.Fab")
		)
		(fp_line
			(start 0.12065 -0.3048)
			(end 0.67945 -0.3048)
			(stroke
				(width 0.1)
				(type default)
			)
			(layer "F.Fab")
		)
		(fp_line
			(start 0.12065 -0.2794)
			(end 0.12065 -0.3048)
			(stroke
				(width 0.1)
				(type default)
			)
			(layer "F.Fab")
		)
		(fp_line
			(start 0.67945 -0.3048)
			(end 0.67945 0.3048)
			(stroke
				(width 0.1)
				(type default)
			)
			(layer "F.Fab")
		)
		(fp_line
			(start 0.67945 0.3048)
			(end 0.120396 0.3048)
			(stroke
				(width 0.1)
				(type default)
			)
			(layer "F.Fab")
		)
		(pad "1" smd circle
			(at -0.40005 0)
			(size 0 0)
			(layers "F.Cu" "F.Mask" "F.Paste")
			(net "SPI_BIC1_CS0_LS01_R2_N")
		)
		(pad "2" smd circle
			(at 0.40005 0)
			(size 0 0)
			(layers "F.Cu" "F.Mask" "F.Paste")
			(net "SPI_BIC1_CS0_LS01_R_N")
		)
	)
	(footprint ""
		(layer "F.Cu")
		(at 390.73074 -343.952322 90)
		(property "Reference" "C745"
			(at 0 0 90)
			(layer "F.SilkS")
			(hide yes)
			(effects
				(font
					(size 1.27 1.27)
				)
			)
		)
		(property "Value" ""
			(at 0 0 90)
			(layer "F.Fab")
			(effects
				(font
					(size 1.27 1.27)
				)
			)
		)
		(duplicate_pad_numbers_are_jumpers no)
		(fp_line
			(start 0.299974 -0.150114)
			(end 0.299974 0.150114)
			(stroke
				(width 0.1)
				(type default)
			)
			(layer "F.Fab")
		)
		(fp_line
			(start -0.299974 -0.150114)
			(end 0.299974 -0.150114)
			(stroke
				(width 0.1)
				(type default)
			)
			(layer "F.Fab")
		)
		(fp_line
			(start 0.299974 0.150114)
			(end -0.299974 0.150114)
			(stroke
				(width 0.1)
				(type default)
			)
			(layer "F.Fab")
		)
		(fp_line
			(start -0.299974 0.150114)
			(end -0.299974 -0.150114)
			(stroke
				(width 0.1)
				(type default)
			)
			(layer "F.Fab")
		)
		(pad "1" smd rect
			(at -0.2667 0 90)
			(size 0.3048 0.381)
			(layers "F.Cu" "F.Mask" "F.Paste")
			(net "P5E_PEX3_STN5_TX_DN<88>")
		)
		(pad "2" smd rect
			(at 0.2667 0 90)
			(size 0.3048 0.381)
			(layers "F.Cu" "F.Mask" "F.Paste")
			(net "P5E_PEX3_STN5_TX_C_DN<88>")
		)
	)
	(footprint ""
		(layer "F.Cu")
		(at 33.11144 -258.234434)
		(property "Reference" "L93"
			(at 0 0 0)
			(layer "F.SilkS")
			(hide yes)
			(effects
				(font
					(size 1.27 1.27)
				)
			)
		)
		(property "Value" ""
			(at 0 0 0)
			(layer "F.Fab")
			(effects
				(font
					(size 1.27 1.27)
				)
			)
		)
		(duplicate_pad_numbers_are_jumpers no)
		(fp_line
			(start -1.63576 -0.8128)
			(end -1.63576 0.8128)
			(stroke
				(width 0.1524)
				(type default)
			)
			(layer "F.SilkS")
		)
		(fp_line
			(start -1.63576 -0.8128)
			(end 1.63576 -0.8128)
			(stroke
				(width 0.1524)
				(type default)
			)
			(layer "F.SilkS")
		)
		(fp_line
			(start 1.63576 -0.8128)
			(end 1.63576 0.8128)
			(stroke
				(width 0.1524)
				(type default)
			)
			(layer "F.SilkS")
		)
		(fp_line
			(start 1.63576 0.8128)
			(end -1.63576 0.8128)
			(stroke
				(width 0.1524)
				(type default)
			)
			(layer "F.SilkS")
		)
		(fp_line
			(start -1.56083 -0.738632)
			(end -1.56083 0.7366)
			(stroke
				(width 0.1)
				(type default)
			)
			(layer "F.Fab")
		)
		(fp_line
			(start -1.56083 0.7366)
			(end -1.524 0.7366)
			(stroke
				(width 0.1)
				(type default)
			)
			(layer "F.Fab")
		)
		(fp_line
			(start -1.524 0.7366)
			(end 1.524 0.7366)
			(stroke
				(width 0.1)
				(type default)
			)
			(layer "F.Fab")
		)
		(fp_line
			(start 1.524 0.7366)
			(end 1.560576 0.7366)
			(stroke
				(width 0.1)
				(type default)
			)
			(layer "F.Fab")
		)
		(fp_line
			(start 1.560576 -0.738632)
			(end -1.56083 -0.738632)
			(stroke
				(width 0.1)
				(type default)
			)
			(layer "F.Fab")
		)
		(fp_line
			(start 1.560576 0.7366)
			(end 1.560576 -0.738632)
			(stroke
				(width 0.1)
				(type default)
			)
			(layer "F.Fab")
		)
		(pad "1" smd rect
			(at -0.94996 0 180)
			(size 1.1176 1.3716)
			(layers "F.Cu" "F.Mask" "F.Paste")
			(net "P1V8_PLL0_PEX0")
		)
		(pad "2" smd rect
			(at 0.94996 0 180)
			(size 1.1176 1.3716)
			(layers "F.Cu" "F.Mask" "F.Paste")
			(net "PCEPLL5_VDDA18_PEX0")
		)
	)
	(footprint ""
		(layer "F.Cu")
		(at 384.834384 -252.356874 -90)
		(property "Reference" "R1431"
			(at 0 0 270)
			(layer "F.SilkS")
			(hide yes)
			(effects
				(font
					(size 1.27 1.27)
				)
			)
		)
		(property "Value" ""
			(at 0 0 270)
			(layer "F.Fab")
			(effects
				(font
					(size 1.27 1.27)
				)
			)
		)
		(duplicate_pad_numbers_are_jumpers no)
		(fp_line
			(start -0.7874 0.4064)
			(end -0.7874 -0.4064)
			(stroke
				(width 0.1524)
				(type default)
			)
			(layer "F.SilkS")
		)
		(fp_line
			(start 0.7874 0.4064)
			(end -0.7874 0.4064)
			(stroke
				(width 0.1524)
				(type default)
			)
			(layer "F.SilkS")
		)
		(fp_line
			(start -0.7874 -0.4064)
			(end 0.7874 -0.4064)
			(stroke
				(width 0.1524)
				(type default)
			)
			(layer "F.SilkS")
		)
		(fp_line
			(start 0.7874 -0.4064)
			(end 0.7874 0.4064)
			(stroke
				(width 0.1524)
				(type default)
			)
			(layer "F.SilkS")
		)
		(fp_line
			(start -0.67945 0.3048)
			(end -0.67945 -0.305054)
			(stroke
				(width 0.1)
				(type default)
			)
			(layer "F.Fab")
		)
		(fp_line
			(start -0.12065 0.3048)
			(end -0.67945 0.3048)
			(stroke
				(width 0.1)
				(type default)
			)
			(layer "F.Fab")
		)
		(fp_line
			(start 0.120396 0.3048)
			(end 0.120396 0.2794)
			(stroke
				(width 0.1)
				(type default)
			)
			(layer "F.Fab")
		)
		(fp_line
			(start 0.67945 0.3048)
			(end 0.120396 0.3048)
			(stroke
				(width 0.1)
				(type default)
			)
			(layer "F.Fab")
		)
		(fp_line
			(start -0.12065 0.2794)
			(end -0.12065 0.3048)
			(stroke
				(width 0.1)
				(type default)
			)
			(layer "F.Fab")
		)
		(fp_line
			(start 0.120396 0.2794)
			(end -0.12065 0.2794)
			(stroke
				(width 0.1)
				(type default)
			)
			(layer "F.Fab")
		)
		(fp_line
			(start -0.12065 -0.2794)
			(end 0.12065 -0.2794)
			(stroke
				(width 0.1)
				(type default)
			)
			(layer "F.Fab")
		)
		(fp_line
			(start 0.12065 -0.2794)
			(end 0.12065 -0.3048)
			(stroke
				(width 0.1)
				(type default)
			)
			(layer "F.Fab")
		)
		(fp_line
			(start 0.12065 -0.3048)
			(end 0.67945 -0.3048)
			(stroke
				(width 0.1)
				(type default)
			)
			(layer "F.Fab")
		)
		(fp_line
			(start 0.67945 -0.3048)
			(end 0.67945 0.3048)
			(stroke
				(width 0.1)
				(type default)
			)
			(layer "F.Fab")
		)
		(fp_line
			(start -0.67945 -0.305054)
			(end -0.12065 -0.305054)
			(stroke
				(width 0.1)
				(type default)
			)
			(layer "F.Fab")
		)
		(fp_line
			(start -0.12065 -0.305054)
			(end -0.12065 -0.2794)
			(stroke
				(width 0.1)
				(type default)
			)
			(layer "F.Fab")
		)
		(pad "1" smd circle
			(at -0.40005 0 270)
			(size 0 0)
			(layers "F.Cu" "F.Mask" "F.Paste")
			(net "GND")
		)
		(pad "2" smd circle
			(at 0.40005 0 270)
			(size 0 0)
			(layers "F.Cu" "F.Mask" "F.Paste")
			(net "PEX3_MODE_SEL6")
		)
	)
	(footprint ""
		(layer "F.Cu")
		(at 315.586364 -343.952322 90)
		(property "Reference" "C547"
			(at 0 0 90)
			(layer "F.SilkS")
			(hide yes)
			(effects
				(font
					(size 1.27 1.27)
				)
			)
		)
		(property "Value" ""
			(at 0 0 90)
			(layer "F.Fab")
			(effects
				(font
					(size 1.27 1.27)
				)
			)
		)
		(duplicate_pad_numbers_are_jumpers no)
		(fp_line
			(start 0.299974 -0.150114)
			(end 0.299974 0.150114)
			(stroke
				(width 0.1)
				(type default)
			)
			(layer "F.Fab")
		)
		(fp_line
			(start -0.299974 -0.150114)
			(end 0.299974 -0.150114)
			(stroke
				(width 0.1)
				(type default)
			)
			(layer "F.Fab")
		)
		(fp_line
			(start 0.299974 0.150114)
			(end -0.299974 0.150114)
			(stroke
				(width 0.1)
				(type default)
			)
			(layer "F.Fab")
		)
		(fp_line
			(start -0.299974 0.150114)
			(end -0.299974 -0.150114)
			(stroke
				(width 0.1)
				(type default)
			)
			(layer "F.Fab")
		)
		(pad "1" smd rect
			(at -0.2667 0 90)
			(size 0.3048 0.381)
			(layers "F.Cu" "F.Mask" "F.Paste")
			(net "P5E_PEX2_STN5_TX_DP<81>")
		)
		(pad "2" smd rect
			(at 0.2667 0 90)
			(size 0.3048 0.381)
			(layers "F.Cu" "F.Mask" "F.Paste")
			(net "P5E_PEX2_STN5_TX_C_DP<81>")
		)
	)
	(footprint ""
		(layer "F.Cu")
		(at 200.691496 -112.39754)
		(property "Reference" "R182"
			(at 0 0 0)
			(layer "F.SilkS")
			(hide yes)
			(effects
				(font
					(size 1.27 1.27)
				)
			)
		)
		(property "Value" ""
			(at 0 0 0)
			(layer "F.Fab")
			(effects
				(font
					(size 1.27 1.27)
				)
			)
		)
		(duplicate_pad_numbers_are_jumpers no)
		(fp_line
			(start -0.7874 -0.4064)
			(end 0.7874 -0.4064)
			(stroke
				(width 0.1524)
				(type default)
			)
			(layer "F.SilkS")
		)
		(fp_line
			(start -0.7874 0.4064)
			(end -0.7874 -0.4064)
			(stroke
				(width 0.1524)
				(type default)
			)
			(layer "F.SilkS")
		)
		(fp_line
			(start 0.7874 -0.4064)
			(end 0.7874 0.4064)
			(stroke
				(width 0.1524)
				(type default)
			)
			(layer "F.SilkS")
		)
		(fp_line
			(start 0.7874 0.4064)
			(end -0.7874 0.4064)
			(stroke
				(width 0.1524)
				(type default)
			)
			(layer "F.SilkS")
		)
		(fp_line
			(start -0.67945 -0.305054)
			(end -0.12065 -0.305054)
			(stroke
				(width 0.1)
				(type default)
			)
			(layer "F.Fab")
		)
		(fp_line
			(start -0.67945 0.3048)
			(end -0.67945 -0.305054)
			(stroke
				(width 0.1)
				(type default)
			)
			(layer "F.Fab")
		)
		(fp_line
			(start -0.12065 -0.305054)
			(end -0.12065 -0.2794)
			(stroke
				(width 0.1)
				(type default)
			)
			(layer "F.Fab")
		)
		(fp_line
			(start -0.12065 -0.2794)
			(end 0.12065 -0.2794)
			(stroke
				(width 0.1)
				(type default)
			)
			(layer "F.Fab")
		)
		(fp_line
			(start -0.12065 0.2794)
			(end -0.12065 0.3048)
			(stroke
				(width 0.1)
				(type default)
			)
			(layer "F.Fab")
		)
		(fp_line
			(start -0.12065 0.3048)
			(end -0.67945 0.3048)
			(stroke
				(width 0.1)
				(type default)
			)
			(layer "F.Fab")
		)
		(fp_line
			(start 0.120396 0.2794)
			(end -0.12065 0.2794)
			(stroke
				(width 0.1)
				(type default)
			)
			(layer "F.Fab")
		)
		(fp_line
			(start 0.120396 0.3048)
			(end 0.120396 0.2794)
			(stroke
				(width 0.1)
				(type default)
			)
			(layer "F.Fab")
		)
		(fp_line
			(start 0.12065 -0.3048)
			(end 0.67945 -0.3048)
			(stroke
				(width 0.1)
				(type default)
			)
			(layer "F.Fab")
		)
		(fp_line
			(start 0.12065 -0.2794)
			(end 0.12065 -0.3048)
			(stroke
				(width 0.1)
				(type default)
			)
			(layer "F.Fab")
		)
		(fp_line
			(start 0.67945 -0.3048)
			(end 0.67945 0.3048)
			(stroke
				(width 0.1)
				(type default)
			)
			(layer "F.Fab")
		)
		(fp_line
			(start 0.67945 0.3048)
			(end 0.120396 0.3048)
			(stroke
				(width 0.1)
				(type default)
			)
			(layer "F.Fab")
		)
		(pad "1" smd circle
			(at -0.40005 0)
			(size 0 0)
			(layers "F.Cu" "F.Mask" "F.Paste")
			(net "NIC3_BIF0_N")
		)
		(pad "2" smd circle
			(at 0.40005 0)
			(size 0 0)
			(layers "F.Cu" "F.Mask" "F.Paste")
			(net "P3V3_AUX")
		)
	)
)
